#ISCELL
  mstr_symbols design_note *
  *
#ISCELL
  mstr_symbols intel_corp_bpage *
  *
#ISCELL
  mstr_symbols gnd *
  page35_i2
#CELL
  chpset_lib skx_ext_b *
  page35_i3
